FILE_TYPE = CONNECTIVITY;
{Allegro Design Entry HDL 17.2-2016 S081 (4005846) 1/11/2022}
"PAGE_NUMBER" = 199;
0"NC";
1"P3V3_AUX_CLK_GEN_VDDMXCK_CK440\g";
2"P3V3_AUX_CLK_GEN_VDDA25M_CK440\g";
3"P3V3_AUX\g";
4"P3V3_AUX_CLK_GEN_VDDXTAL_CK440\g";
5"P3V3_AUX_CLK_GEN_VDD_CK440\g";
6"P3V3_AUX\g";
7"P3V3_AUX_CLK_GEN_VDDPT_CK440\g";
8"P3V3_AUX_CLK_GEN_VDDA100M_CK440\g";
9"P3V3_AUX\g";
10"GND\g";
11"GND\g";
12"GND\g";
13"GND\g";
14"GND\g";
15"GND\g";
%"Q_CAP"
"1","(-11850,7450)","0","pure_quanta","I19";
;
PART_NUMBER"CH6101ME900"
TOLERANCE"20%"
MATERIAL"X6S"
PACK_TYPE"C0603"
VOLTAGE"6.3V"
VALUE"10UF"
$LOCATION"C108"
CDS_LIB"pure_quanta"
CDS_LOCATION"C108"
$SEC"1"
CDS_SEC"1";
"B"
$PN"2"15;
"A"
$PN"1"5;
%"Q_INDUCTOR"
"1","(-12075,7700)","0","pure_quanta","I20";
;
PART_NUMBER"CX601T05003"
PACK_TYPE"SMLF"
VALUE"FCM2012KF-601T/0.5A"
MATERIAL"IND"
$LOCATION"L1"
CDS_LIB"pure_quanta"
NEEDS_NO_SIZE"TRUE"
CDS_LOCATION"L1"
$SEC"1"
CDS_SEC"1";
"1"
$PN"1"9;
"2"
$PN"2"5;
%"UNIVERSAL_POWER"
"1","(-12400,7975)","0","logical_power","I21";
;
HDL_POWER"P3V3_AUX"
CDS_LIB"logical_power";
"A"9;
%"UNIVERSAL_POWER"
"1","(-8850,7825)","0","logical_power","I3";
;
HDL_POWER"P3V3_AUX_CLK_GEN_VDDA100M_CK440"
CDS_LIB"logical_power";
"A"8;
%"UNIVERSAL_POWER"
"1","(-8850,6600)","0","logical_power","I31";
;
HDL_POWER"P3V3_AUX_CLK_GEN_VDDA25M_CK440"
CDS_LIB"logical_power";
"A"2;
%"UNIVERSAL_POWER"
"1","(-10200,6600)","0","logical_power","I35";
;
HDL_POWER"P3V3_AUX_CLK_GEN_VDDXTAL_CK440"
CDS_LIB"logical_power";
"A"4;
%"Q_RES"
"1","(-9775,6450)","0","pure_quanta","I36";
;
PART_NUMBER"CS-1003F900"
PACK_TYPE"0603LF"
TOLERANCE"1%"
WATTAGE"1/10W"
VALUE"1"
MATERIAL"CHIP"
$LOCATION"R442"
CDS_LIB"pure_quanta"
CDS_LOCATION"R442"
$SEC"1"
CDS_SEC"1";
"B"
$PN"2"2;
"A"
$PN"1"4;
%"Q_INDUCTOR"
"1","(-12075,6475)","0","pure_quanta","I41";
;
PART_NUMBER"CX601T05003"
VALUE"FCM2012KF-601T/0.5A"
MATERIAL"IND"
PACK_TYPE"SMLF"
$LOCATION"L13"
NEEDS_NO_SIZE"TRUE"
CDS_LIB"pure_quanta"
CDS_LOCATION"L13"
$SEC"1"
CDS_SEC"1";
"1"
$PN"1"3;
"2"
$PN"2"4;
%"UNIVERSAL_POWER"
"1","(-12400,6750)","0","logical_power","I42";
;
HDL_POWER"P3V3_AUX"
CDS_LIB"logical_power";
"A"3;
%"Q_CAP"
"1","(-11500,6225)","0","pure_quanta","I43";
;
PART_NUMBER"CH5104KEB02"
PACK_TYPE"C0402"
MATERIAL"X6S"
VOLTAGE"25V"
TOLERANCE"10%"
VALUE"1UF"
$LOCATION"C1311"
CDS_LIB"pure_quanta"
BOM_COST"VR_SYSTEM "
CDS_LOCATION"C1311"
$SEC"1"
CDS_SEC"1";
"B"
$PN"2"12;
"A"
$PN"1"4;
%"Q_CAP"
"1","(-11850,6225)","0","pure_quanta","I44";
;
PART_NUMBER"CH6101ME900"
VALUE"10UF"
TOLERANCE"20%"
PACK_TYPE"C0603"
VOLTAGE"6.3V"
MATERIAL"X6S"
$LOCATION"C1309"
CDS_LIB"pure_quanta"
CDS_LOCATION"C1309"
$SEC"1"
CDS_SEC"1";
"B"
$PN"2"12;
"A"
$PN"1"4;
%"Q_CAP"
"1","(-9250,6225)","0","pure_quanta","I48";
;
PART_NUMBER"CH6101ME900"
PACK_TYPE"C0603"
VALUE"10UF"
VOLTAGE"6.3V"
TOLERANCE"20%"
MATERIAL"X6S"
$LOCATION"C1313"
CDS_LIB"pure_quanta"
CDS_LOCATION"C1313"
$SEC"1"
CDS_SEC"1";
"B"
$PN"2"13;
"A"
$PN"1"2;
%"UNIVERSAL_POWER"
"1","(-8850,5300)","0","logical_power","I51";
;
HDL_POWER"P3V3_AUX_CLK_GEN_VDDPT_CK440"
CDS_LIB"logical_power";
"A"7;
%"Q_CAP"
"1","(-9250,4925)","0","pure_quanta","I53";
;
PART_NUMBER"CH6101ME900"
PACK_TYPE"C0603"
VALUE"10UF"
TOLERANCE"20%"
VOLTAGE"6.3V"
MATERIAL"X6S"
$LOCATION"C1314"
CDS_LIB"pure_quanta"
CDS_LOCATION"C1314"
$SEC"1"
CDS_SEC"1";
"B"
$PN"2"10;
"A"
$PN"1"7;
%"Q_RES"
"1","(-9775,5150)","0","pure_quanta","I55";
;
PART_NUMBER"CS-1003F900"
PACK_TYPE"0603LF"
WATTAGE"1/10W"
TOLERANCE"1%"
MATERIAL"CHIP"
VALUE"1"
$LOCATION"R447"
CDS_LIB"pure_quanta"
CDS_LOCATION"R447"
$SEC"1"
CDS_SEC"1";
"B"
$PN"2"7;
"A"
$PN"1"1;
%"UNIVERSAL_POWER"
"1","(-10200,5300)","0","logical_power","I56";
;
HDL_POWER"P3V3_AUX_CLK_GEN_VDDMXCK_CK440"
CDS_LIB"logical_power";
"A"1;
%"Q_CAP"
"1","(-11500,4925)","0","pure_quanta","I58";
;
PART_NUMBER"CH5104KEB02"
PACK_TYPE"C0402"
VALUE"1UF"
VOLTAGE"25V"
MATERIAL"X6S"
TOLERANCE"10%"
$LOCATION"C1312"
CDS_LIB"pure_quanta"
BOM_COST"VR_SYSTEM "
CDS_LOCATION"C1312"
$SEC"1"
CDS_SEC"1";
"B"
$PN"2"11;
"A"
$PN"1"1;
%"Q_CAP"
"1","(-11850,4925)","0","pure_quanta","I59";
;
PART_NUMBER"CH6101ME900"
PACK_TYPE"C0603"
VALUE"10UF"
VOLTAGE"6.3V"
TOLERANCE"20%"
MATERIAL"X6S"
$LOCATION"C1310"
CDS_LIB"pure_quanta"
CDS_LOCATION"C1310"
$SEC"1"
CDS_SEC"1";
"B"
$PN"2"11;
"A"
$PN"1"1;
%"Q_CAP"
"1","(-9250,7450)","0","pure_quanta","I6";
;
PART_NUMBER"CH6101ME900"
PACK_TYPE"C0603"
VALUE"10UF"
MATERIAL"X6S"
TOLERANCE"20%"
VOLTAGE"6.3V"
$LOCATION"C172"
CDS_LIB"pure_quanta"
CDS_LOCATION"C172"
$SEC"1"
CDS_SEC"1";
"B"
$PN"2"14;
"A"
$PN"1"8;
%"Q_INDUCTOR"
"1","(-12075,5175)","0","pure_quanta","I60";
;
PART_NUMBER"CX601T05003"
VALUE"FCM2012KF-601T/0.5A"
MATERIAL"IND"
PACK_TYPE"SMLF"
$LOCATION"L14"
CDS_LIB"pure_quanta"
NEEDS_NO_SIZE"TRUE"
CDS_LOCATION"L14"
$SEC"1"
CDS_SEC"1";
"1"
$PN"1"6;
"2"
$PN"2"1;
%"UNIVERSAL_POWER"
"1","(-12400,5450)","0","logical_power","I61";
;
HDL_POWER"P3V3_AUX"
CDS_LIB"logical_power";
"A"6;
%"UNIVERSAL_GND"
"1","(-10900,7075)","0","logical_power","I69";
;
CDS_LIB"logical_power"
HDL_POWER"GND";
"A"15;
%"Q_RES"
"1","(-9775,7675)","0","pure_quanta","I7";
;
PART_NUMBER"CS-1003F900"
PACK_TYPE"0603LF"
WATTAGE"1/10W"
TOLERANCE"1%"
MATERIAL"CHIP"
VALUE"1"
$LOCATION"R519"
CDS_LIB"pure_quanta"
CDS_LOCATION"R519"
$SEC"1"
CDS_SEC"1";
"B"
$PN"2"8;
"A"
$PN"1"5;
%"UNIVERSAL_GND"
"1","(-8850,7075)","0","logical_power","I70";
;
CDS_LIB"logical_power"
HDL_POWER"GND";
"A"14;
%"UNIVERSAL_GND"
"1","(-8850,5850)","0","logical_power","I71";
;
CDS_LIB"logical_power"
HDL_POWER"GND";
"A"13;
%"UNIVERSAL_GND"
"1","(-10900,5850)","0","logical_power","I72";
;
CDS_LIB"logical_power"
HDL_POWER"GND";
"A"12;
%"UNIVERSAL_GND"
"1","(-10400,4525)","0","logical_power","I73";
;
CDS_LIB"logical_power"
HDL_POWER"GND";
"A"11;
%"UNIVERSAL_GND"
"1","(-8850,4550)","0","logical_power","I74";
;
CDS_LIB"logical_power"
HDL_POWER"GND";
"A"10;
%"Q_CAP"
"1","(-11150,7450)","0","pure_quanta","I76";
;
PART_NUMBER"CH3474K1B04"
MATERIAL"X7R"
PACK_TYPE"C0402"
TOLERANCE"10%"
VALUE"0.047UF"
VOLTAGE"25V"
LOCATION"C110"
CDS_LIB"pure_quanta"
$SEC"1"
CDS_SEC"1";
"B"
$PN"2"15;
"A"
$PN"1"5;
%"Q_CAP"
"1","(-10900,7450)","0","pure_quanta","I77";
;
PART_NUMBER"CH3474K1B04"
VALUE"0.047UF"
PACK_TYPE"C0402"
VOLTAGE"25V"
TOLERANCE"10%"
MATERIAL"X7R"
LOCATION"C171"
CDS_LIB"pure_quanta"
$SEC"1"
CDS_SEC"1";
"B"
$PN"2"15;
"A"
$PN"1"5;
%"Q_CAP"
"1","(-8850,7450)","0","pure_quanta","I78";
;
PART_NUMBER"CH3474K1B04"
MATERIAL"X7R"
PACK_TYPE"C0402"
TOLERANCE"10%"
VOLTAGE"25V"
VALUE"0.047UF"
LOCATION"C173"
CDS_LIB"pure_quanta"
$SEC"1"
CDS_SEC"1";
"B"
$PN"2"14;
"A"
$PN"1"8;
%"Q_CAP"
"1","(-8850,6225)","0","pure_quanta","I79";
;
PART_NUMBER"CH3474K1B04"
MATERIAL"X7R"
TOLERANCE"10%"
VOLTAGE"25V"
PACK_TYPE"C0402"
VALUE"0.047UF"
LOCATION"C114"
CDS_LIB"pure_quanta"
$SEC"1"
CDS_SEC"1";
"B"
$PN"2"13;
"A"
$PN"1"2;
%"UNIVERSAL_POWER"
"1","(-10200,7825)","0","logical_power","I8";
;
HDL_POWER"P3V3_AUX_CLK_GEN_VDD_CK440"
CDS_LIB"logical_power";
"A"5;
%"Q_CAP"
"1","(-10900,6225)","0","pure_quanta","I80";
;
PART_NUMBER"CH3474K1B04"
MATERIAL"X7R"
TOLERANCE"10%"
PACK_TYPE"C0402"
VALUE"0.047UF"
VOLTAGE"25V"
LOCATION"C112"
CDS_LIB"pure_quanta"
$SEC"1"
CDS_SEC"1";
"B"
$PN"2"12;
"A"
$PN"1"4;
%"Q_CAP"
"1","(-11150,6225)","0","pure_quanta","I81";
;
PART_NUMBER"CH3474K1B04"
PACK_TYPE"C0402"
VALUE"0.047UF"
TOLERANCE"10%"
VOLTAGE"25V"
MATERIAL"X7R"
LOCATION"C111"
CDS_LIB"pure_quanta"
$SEC"1"
CDS_SEC"1";
"B"
$PN"2"12;
"A"
$PN"1"4;
%"Q_CAP"
"1","(-11500,7450)","0","pure_quanta","I82";
;
PART_NUMBER"CH5104KEB02"
VALUE"1UF"
MATERIAL"X6S"
PACK_TYPE"C0402"
TOLERANCE"10%"
VOLTAGE"25V"
LOCATION"C107"
BOM_COST"VR_SYSTEM "
CDS_LIB"pure_quanta"
$SEC"1"
CDS_SEC"1";
"B"
$PN"2"15;
"A"
$PN"1"5;
%"Q_CAP"
"1","(-8850,4925)","0","pure_quanta","I85";
;
PART_NUMBER"CH3474K1B04"
MATERIAL"X7R"
TOLERANCE"10%"
VOLTAGE"25V"
PACK_TYPE"C0402"
VALUE"0.047UF"
LOCATION"C120"
CDS_LIB"pure_quanta"
$SEC"1"
CDS_SEC"1";
"B"
$PN"2"10;
"A"
$PN"1"7;
%"Q_CAP"
"1","(-10400,4925)","0","pure_quanta","I86";
;
PART_NUMBER"CH3474K1B04"
VALUE"0.047UF"
PACK_TYPE"C0402"
VOLTAGE"25V"
TOLERANCE"10%"
MATERIAL"X7R"
LOCATION"C119"
CDS_LIB"pure_quanta"
$SEC"1"
CDS_SEC"1";
"B"
$PN"2"11;
"A"
$PN"1"1;
%"Q_CAP"
"1","(-10650,4925)","0","pure_quanta","I87";
;
PART_NUMBER"CH3474K1B04"
VALUE"0.047UF"
PACK_TYPE"C0402"
VOLTAGE"25V"
TOLERANCE"10%"
MATERIAL"X7R"
LOCATION"C117"
CDS_LIB"pure_quanta"
$SEC"1"
CDS_SEC"1";
"B"
$PN"2"11;
"A"
$PN"1"1;
%"Q_CAP"
"1","(-10900,4925)","0","pure_quanta","I88";
;
PART_NUMBER"CH3474K1B04"
PACK_TYPE"C0402"
MATERIAL"X7R"
TOLERANCE"10%"
VALUE"0.047UF"
VOLTAGE"25V"
LOCATION"C116"
CDS_LIB"pure_quanta"
$SEC"1"
CDS_SEC"1";
"B"
$PN"2"11;
"A"
$PN"1"1;
%"Q_CAP"
"1","(-11150,4925)","0","pure_quanta","I89";
;
PART_NUMBER"CH3474K1B04"
VALUE"0.047UF"
VOLTAGE"25V"
TOLERANCE"10%"
MATERIAL"X7R"
PACK_TYPE"C0402"
LOCATION"C115"
CDS_LIB"pure_quanta"
$SEC"1"
CDS_SEC"1";
"B"
$PN"2"11;
"A"
$PN"1"1;
END.
